(kicad_pcb
	(version 20241229)
	(generator "pcbnew")
	(generator_version "9.0")
	(general
		(thickness 1.599998)
		(legacy_teardrops no)
	)
	(paper "A4")
	(title_block
		(title "Artix - Datacenter Secure Control Module (DC-SCM)")
		(date "2024-11-06")
		(rev "1.1.3")
		(comment 9 "footprints 111-115 of 544")
	)
	(layers
		(0 "F.Cu" signal)
		(4 "In1.Cu" signal)
		(6 "In2.Cu" signal)
		(8 "In3.Cu" signal)
		(10 "In4.Cu" signal)
		(12 "In5.Cu" signal)
		(14 "In6.Cu" signal)
		(2 "B.Cu" signal)
		(9 "F.Adhes" user "F.Adhesive")
		(11 "B.Adhes" user "B.Adhesive")
		(13 "F.Paste" user)
		(15 "B.Paste" user)
		(5 "F.SilkS" user "F.Silkscreen")
		(7 "B.SilkS" user "B.Silkscreen")
		(1 "F.Mask" user)
		(3 "B.Mask" user)
		(17 "Dwgs.User" user "User.Drawings")
		(19 "Cmts.User" user "User.Comments")
		(21 "Eco1.User" user "User.Eco1")
		(23 "Eco2.User" user "User.Eco2")
		(25 "Edge.Cuts" user)
		(27 "Margin" user)
		(31 "F.CrtYd" user "F.Courtyard")
		(29 "B.CrtYd" user "B.Courtyard")
		(35 "F.Fab" user)
		(33 "B.Fab" user)
	)
	(footprint "antmicro-footprints:R_0402_1005Metric"
		(layer "F.Cu")
		(at 89.975 105.475)
		(descr "Resistor SMD 0402")
		(tags "resistor SMD 0402")
		(property "Reference" "R14"
			(at 0.725 0.425 0)
			(layer "F.SilkS")
			(effects
				(font
					(size 0.7 0.7)
					(thickness 0.15)
				)
				(justify left bottom)
			)
		)
		(property "Value" "R_0R_0402"
			(at 0 1.4 0)
			(layer "F.Fab")
			(effects
				(font
					(size 0.7 0.7)
					(thickness 0.15)
				)
				(justify left bottom)
			)
		)
		(property "Datasheet" "https://industrial.panasonic.com/cdbs/www-data/pdf/RDA0000/AOA0000C301.pdf"
			(at 0 0 0)
			(layer "F.Fab")
			(hide yes)
			(effects
				(font
					(size 1.27 1.27)
					(thickness 0.15)
				)
			)
		)
		(property "Description" "SMD Chip Resistor, Jumper, 0 ohm, 100 mW, 0402 [1005 Metric], Thick Film, General Purpose"
			(at 0 0 0)
			(layer "F.Fab")
			(hide yes)
			(effects
				(font
					(size 1.27 1.27)
					(thickness 0.15)
				)
			)
		)
		(property "Author" "Antmicro"
			(at 0 0 0)
			(layer "F.Fab")
			(hide yes)
			(effects
				(font
					(size 1 1)
					(thickness 0.15)
				)
			)
		)
		(property "Current" "1A"
			(at 0 0 0)
			(layer "F.Fab")
			(hide yes)
			(effects
				(font
					(size 1 1)
					(thickness 0.15)
				)
			)
		)
		(property "License" "Apache-2.0"
			(at 0 0 0)
			(layer "F.Fab")
			(hide yes)
			(effects
				(font
					(size 1 1)
					(thickness 0.15)
				)
			)
		)
		(property "MPN" "ERJ2GE0R00X"
			(at 0 0 0)
			(layer "F.Fab")
			(hide yes)
			(effects
				(font
					(size 1 1)
					(thickness 0.15)
				)
			)
		)
		(property "Manufacturer" "Panasonic"
			(at 0 0 0)
			(layer "F.Fab")
			(hide yes)
			(effects
				(font
					(size 1 1)
					(thickness 0.15)
				)
			)
		)
		(property "Tolerance" "~"
			(at 0 0 0)
			(layer "F.Fab")
			(hide yes)
			(effects
				(font
					(size 1 1)
					(thickness 0.15)
				)
			)
		)
		(property "Val" "0R"
			(at 0 0 0)
			(layer "F.Fab")
			(hide yes)
			(effects
				(font
					(size 1 1)
					(thickness 0.15)
				)
			)
		)
		(sheetname "/Power supply/")
		(sheetfile "power-supply.kicad_sch")
		(attr smd)
		(fp_rect
			(start -0.925 -0.47)
			(end 0.925 0.47)
			(stroke
				(width 0.05)
				(type default)
			)
			(fill no)
			(layer "F.CrtYd")
		)
		(fp_rect
			(start -0.5 -0.25)
			(end 0.5 0.25)
			(stroke
				(width 0.15)
				(type solid)
			)
			(fill no)
			(layer "F.Fab")
		)
		(pad "1" smd roundrect
			(at -0.48 0)
			(size 0.59 0.64)
			(layers "F.Cu" "F.Mask" "F.Paste")
			(roundrect_rratio 0.25)
			(net 314 "Net-(U10-EN)")
			(pintype "passive")
		)
		(pad "2" smd roundrect
			(at 0.48 0)
			(size 0.59 0.64)
			(layers "F.Cu" "F.Mask" "F.Paste")
			(roundrect_rratio 0.25)
			(net 297 "/Power supply/VCCIO_EN")
			(pintype "passive")
		)
	)
	(footprint "antmicro-footprints:R_0402_1005Metric"
		(layer "F.Cu")
		(at 89.975 98.075)
		(descr "Resistor SMD 0402")
		(tags "resistor SMD 0402")
		(property "Reference" "R15"
			(at 0.725 0.425 0)
			(layer "F.SilkS")
			(effects
				(font
					(size 0.7 0.7)
					(thickness 0.15)
				)
				(justify left bottom)
			)
		)
		(property "Value" "R_0R_0402"
			(at 0 1.4 0)
			(layer "F.Fab")
			(effects
				(font
					(size 0.7 0.7)
					(thickness 0.15)
				)
				(justify left bottom)
			)
		)
		(property "Datasheet" "https://industrial.panasonic.com/cdbs/www-data/pdf/RDA0000/AOA0000C301.pdf"
			(at 0 0 0)
			(layer "F.Fab")
			(hide yes)
			(effects
				(font
					(size 1.27 1.27)
					(thickness 0.15)
				)
			)
		)
		(property "Description" "SMD Chip Resistor, Jumper, 0 ohm, 100 mW, 0402 [1005 Metric], Thick Film, General Purpose"
			(at 0 0 0)
			(layer "F.Fab")
			(hide yes)
			(effects
				(font
					(size 1.27 1.27)
					(thickness 0.15)
				)
			)
		)
		(property "Author" "Antmicro"
			(at 0 0 0)
			(layer "F.Fab")
			(hide yes)
			(effects
				(font
					(size 1 1)
					(thickness 0.15)
				)
			)
		)
		(property "Current" "1A"
			(at 0 0 0)
			(layer "F.Fab")
			(hide yes)
			(effects
				(font
					(size 1 1)
					(thickness 0.15)
				)
			)
		)
		(property "License" "Apache-2.0"
			(at 0 0 0)
			(layer "F.Fab")
			(hide yes)
			(effects
				(font
					(size 1 1)
					(thickness 0.15)
				)
			)
		)
		(property "MPN" "ERJ2GE0R00X"
			(at 0 0 0)
			(layer "F.Fab")
			(hide yes)
			(effects
				(font
					(size 1 1)
					(thickness 0.15)
				)
			)
		)
		(property "Manufacturer" "Panasonic"
			(at 0 0 0)
			(layer "F.Fab")
			(hide yes)
			(effects
				(font
					(size 1 1)
					(thickness 0.15)
				)
			)
		)
		(property "Tolerance" "~"
			(at 0 0 0)
			(layer "F.Fab")
			(hide yes)
			(effects
				(font
					(size 1 1)
					(thickness 0.15)
				)
			)
		)
		(property "Val" "0R"
			(at 0 0 0)
			(layer "F.Fab")
			(hide yes)
			(effects
				(font
					(size 1 1)
					(thickness 0.15)
				)
			)
		)
		(sheetname "/Power supply/")
		(sheetfile "power-supply.kicad_sch")
		(attr smd)
		(fp_rect
			(start -0.925 -0.47)
			(end 0.925 0.47)
			(stroke
				(width 0.05)
				(type default)
			)
			(fill no)
			(layer "F.CrtYd")
		)
		(fp_rect
			(start -0.5 -0.25)
			(end 0.5 0.25)
			(stroke
				(width 0.15)
				(type solid)
			)
			(fill no)
			(layer "F.Fab")
		)
		(pad "1" smd roundrect
			(at -0.48 0)
			(size 0.59 0.64)
			(layers "F.Cu" "F.Mask" "F.Paste")
			(roundrect_rratio 0.25)
			(net 315 "Net-(U11-EN)")
			(pintype "passive")
		)
		(pad "2" smd roundrect
			(at 0.48 0)
			(size 0.59 0.64)
			(layers "F.Cu" "F.Mask" "F.Paste")
			(roundrect_rratio 0.25)
			(net 296 "/Power supply/VCCAUX_EN")
			(pintype "passive")
		)
	)
	(footprint "antmicro-footprints:R_0402_1005Metric"
		(layer "F.Cu")
		(at 89.975 83.375)
		(descr "Resistor SMD 0402")
		(tags "resistor SMD 0402")
		(property "Reference" "R16"
			(at 0.825 0.325 0)
			(layer "F.SilkS")
			(effects
				(font
					(size 0.7 0.7)
					(thickness 0.15)
				)
				(justify left bottom)
			)
		)
		(property "Value" "R_0R_0402"
			(at 0 1.4 0)
			(layer "F.Fab")
			(effects
				(font
					(size 0.7 0.7)
					(thickness 0.15)
				)
				(justify left bottom)
			)
		)
		(property "Datasheet" "https://industrial.panasonic.com/cdbs/www-data/pdf/RDA0000/AOA0000C301.pdf"
			(at 0 0 0)
			(layer "F.Fab")
			(hide yes)
			(effects
				(font
					(size 1.27 1.27)
					(thickness 0.15)
				)
			)
		)
		(property "Description" "SMD Chip Resistor, Jumper, 0 ohm, 100 mW, 0402 [1005 Metric], Thick Film, General Purpose"
			(at 0 0 0)
			(layer "F.Fab")
			(hide yes)
			(effects
				(font
					(size 1.27 1.27)
					(thickness 0.15)
				)
			)
		)
		(property "Author" "Antmicro"
			(at 0 0 0)
			(layer "F.Fab")
			(hide yes)
			(effects
				(font
					(size 1 1)
					(thickness 0.15)
				)
			)
		)
		(property "Current" "1A"
			(at 0 0 0)
			(layer "F.Fab")
			(hide yes)
			(effects
				(font
					(size 1 1)
					(thickness 0.15)
				)
			)
		)
		(property "License" "Apache-2.0"
			(at 0 0 0)
			(layer "F.Fab")
			(hide yes)
			(effects
				(font
					(size 1 1)
					(thickness 0.15)
				)
			)
		)
		(property "MPN" "ERJ2GE0R00X"
			(at 0 0 0)
			(layer "F.Fab")
			(hide yes)
			(effects
				(font
					(size 1 1)
					(thickness 0.15)
				)
			)
		)
		(property "Manufacturer" "Panasonic"
			(at 0 0 0)
			(layer "F.Fab")
			(hide yes)
			(effects
				(font
					(size 1 1)
					(thickness 0.15)
				)
			)
		)
		(property "Tolerance" "~"
			(at 0 0 0)
			(layer "F.Fab")
			(hide yes)
			(effects
				(font
					(size 1 1)
					(thickness 0.15)
				)
			)
		)
		(property "Val" "0R"
			(at 0 0 0)
			(layer "F.Fab")
			(hide yes)
			(effects
				(font
					(size 1 1)
					(thickness 0.15)
				)
			)
		)
		(sheetname "/Power supply/")
		(sheetfile "power-supply.kicad_sch")
		(attr smd)
		(fp_rect
			(start -0.925 -0.47)
			(end 0.925 0.47)
			(stroke
				(width 0.05)
				(type default)
			)
			(fill no)
			(layer "F.CrtYd")
		)
		(fp_rect
			(start -0.5 -0.25)
			(end 0.5 0.25)
			(stroke
				(width 0.15)
				(type solid)
			)
			(fill no)
			(layer "F.Fab")
		)
		(pad "1" smd roundrect
			(at -0.48 0)
			(size 0.59 0.64)
			(layers "F.Cu" "F.Mask" "F.Paste")
			(roundrect_rratio 0.25)
			(net 319 "Net-(U12-EN)")
			(pintype "passive")
		)
		(pad "2" smd roundrect
			(at 0.48 0)
			(size 0.59 0.64)
			(layers "F.Cu" "F.Mask" "F.Paste")
			(roundrect_rratio 0.25)
			(net 295 "/Power supply/VCCINT_EN")
			(pintype "passive")
		)
	)
	(footprint "antmicro-footprints:R_0402_1005Metric"
		(layer "F.Cu")
		(at 89.975 90.775)
		(descr "Resistor SMD 0402")
		(tags "resistor SMD 0402")
		(property "Reference" "R138"
			(at 0.725 0.425 0)
			(layer "F.SilkS")
			(effects
				(font
					(size 0.7 0.7)
					(thickness 0.15)
				)
				(justify left bottom)
			)
		)
		(property "Value" "R_0R_0402"
			(at 0 1.4 0)
			(layer "F.Fab")
			(effects
				(font
					(size 0.7 0.7)
					(thickness 0.15)
				)
				(justify left bottom)
			)
		)
		(property "Datasheet" "https://industrial.panasonic.com/cdbs/www-data/pdf/RDA0000/AOA0000C301.pdf"
			(at 0 0 0)
			(layer "F.Fab")
			(hide yes)
			(effects
				(font
					(size 1.27 1.27)
					(thickness 0.15)
				)
			)
		)
		(property "Description" "SMD Chip Resistor, Jumper, 0 ohm, 100 mW, 0402 [1005 Metric], Thick Film, General Purpose"
			(at 0 0 0)
			(layer "F.Fab")
			(hide yes)
			(effects
				(font
					(size 1.27 1.27)
					(thickness 0.15)
				)
			)
		)
		(property "Author" "Antmicro"
			(at 0 0 0)
			(layer "F.Fab")
			(hide yes)
			(effects
				(font
					(size 1 1)
					(thickness 0.15)
				)
			)
		)
		(property "Current" "1A"
			(at 0 0 0)
			(layer "F.Fab")
			(hide yes)
			(effects
				(font
					(size 1 1)
					(thickness 0.15)
				)
			)
		)
		(property "License" "Apache-2.0"
			(at 0 0 0)
			(layer "F.Fab")
			(hide yes)
			(effects
				(font
					(size 1 1)
					(thickness 0.15)
				)
			)
		)
		(property "MPN" "ERJ2GE0R00X"
			(at 0 0 0)
			(layer "F.Fab")
			(hide yes)
			(effects
				(font
					(size 1 1)
					(thickness 0.15)
				)
			)
		)
		(property "Manufacturer" "Panasonic"
			(at 0 0 0)
			(layer "F.Fab")
			(hide yes)
			(effects
				(font
					(size 1 1)
					(thickness 0.15)
				)
			)
		)
		(property "Tolerance" "~"
			(at 0 0 0)
			(layer "F.Fab")
			(hide yes)
			(effects
				(font
					(size 1 1)
					(thickness 0.15)
				)
			)
		)
		(property "Val" "0R"
			(at 0 0 0)
			(layer "F.Fab")
			(hide yes)
			(effects
				(font
					(size 1 1)
					(thickness 0.15)
				)
			)
		)
		(sheetname "/Power supply/")
		(sheetfile "power-supply.kicad_sch")
		(attr smd)
		(fp_rect
			(start -0.925 -0.47)
			(end 0.925 0.47)
			(stroke
				(width 0.05)
				(type default)
			)
			(fill no)
			(layer "F.CrtYd")
		)
		(fp_rect
			(start -0.5 -0.25)
			(end 0.5 0.25)
			(stroke
				(width 0.15)
				(type solid)
			)
			(fill no)
			(layer "F.Fab")
		)
		(pad "1" smd roundrect
			(at -0.48 0)
			(size 0.59 0.64)
			(layers "F.Cu" "F.Mask" "F.Paste")
			(roundrect_rratio 0.25)
			(net 343 "Net-(U13-EN)")
			(pintype "passive")
		)
		(pad "2" smd roundrect
			(at 0.48 0)
			(size 0.59 0.64)
			(layers "F.Cu" "F.Mask" "F.Paste")
			(roundrect_rratio 0.25)
			(net 297 "/Power supply/VCCIO_EN")
			(pintype "passive")
		)
	)
	(footprint "antmicro-footprints:SOIC-8_5.3x5.3x2mm_P1.27mm"
		(layer "F.Cu")
		(at 66.47 137.795 90)
		(descr "8-Pin SOIC 208-mil")
		(property "Reference" "U4"
			(at -0.0015 -3.2 90)
			(layer "F.SilkS")
			(effects
				(font
					(size 0.7 0.7)
					(thickness 0.15)
				)
				(justify left bottom)
			)
		)
		(property "Value" "W25Q32JW_SOIC-8"
			(at 0 3.8 90)
			(layer "F.Fab")
			(effects
				(font
					(size 0.7 0.7)
					(thickness 0.15)
				)
				(justify left bottom)
			)
		)
		(property "Datasheet" "https://www.mouser.com/datasheet/2/949/w25q32jw_spi_revf_09042018-1489621.pdf"
			(at 0 0 90)
			(layer "F.Fab")
			(hide yes)
			(effects
				(font
					(size 1.27 1.27)
					(thickness 0.15)
				)
			)
		)
		(property "Description" "FLASH - NOR Memory IC 32Mbit SPI - Quad I/O 133 MHz 8-SOIC"
			(at 0 0 90)
			(layer "F.Fab")
			(hide yes)
			(effects
				(font
					(size 1.27 1.27)
					(thickness 0.15)
				)
			)
		)
		(property "Author" "Antmicro"
			(at 204.265 71.325 0)
			(layer "F.Fab")
			(hide yes)
			(effects
				(font
					(size 1 1)
					(thickness 0.15)
				)
			)
		)
		(property "License" "Apache-2.0"
			(at 204.265 71.325 0)
			(layer "F.Fab")
			(hide yes)
			(effects
				(font
					(size 1 1)
					(thickness 0.15)
				)
			)
		)
		(property "MPN" "W25Q32JWSSIQ"
			(at 204.265 71.325 0)
			(layer "F.Fab")
			(hide yes)
			(effects
				(font
					(size 1 1)
					(thickness 0.15)
				)
			)
		)
		(property "Manufacturer" "Winbond"
			(at 204.265 71.325 0)
			(layer "F.Fab")
			(hide yes)
			(effects
				(font
					(size 1 1)
					(thickness 0.15)
				)
			)
		)
		(sheetname "/RoT/")
		(sheetfile "rot.kicad_sch")
		(attr smd)
		(fp_line
			(start -2.8 -2.641)
			(end -4.4 -2.641)
			(stroke
				(width 0.15)
				(type solid)
			)
			(layer "F.SilkS")
		)
		(fp_circle
			(center -4.85 -1.905)
			(end -4.8 -1.855)
			(stroke
				(width 0.15)
				(type solid)
			)
			(fill yes)
			(layer "F.SilkS")
		)
		(fp_rect
			(start 4.675 -3)
			(end -4.675 3)
			(stroke
				(width 0.05)
				(type solid)
			)
			(fill no)
			(layer "F.CrtYd")
		)
		(fp_line
			(start 2.64 -2.641)
			(end 2.64 2.64)
			(stroke
				(width 0.15)
				(type solid)
			)
			(layer "F.Fab")
		)
		(fp_line
			(start -2.641 -2.641)
			(end 2.64 -2.641)
			(stroke
				(width 0.15)
				(type solid)
			)
			(layer "F.Fab")
		)
		(fp_line
			(start -2.641 -1.371)
			(end -1.371 -2.641)
			(stroke
				(width 0.15)
				(type solid)
			)
			(layer "F.Fab")
		)
		(fp_line
			(start 2.64 2.64)
			(end -2.641 2.64)
			(stroke
				(width 0.15)
				(type solid)
			)
			(layer "F.Fab")
		)
		(fp_line
			(start -2.641 2.64)
			(end -2.641 -2.641)
			(stroke
				(width 0.15)
				(type solid)
			)
			(layer "F.Fab")
		)
		(pad "1" smd roundrect
			(at -3.601 -1.905 180)
			(size 0.65 1.65)
			(layers "F.Cu" "F.Mask" "F.Paste")
			(roundrect_rratio 0.25)
			(net 140 "QSPIA2_CS_N")
			(pinfunction "~{CS}")
			(pintype "input")
		)
		(pad "2" smd roundrect
			(at -3.601 -0.635 180)
			(size 0.65 1.65)
			(layers "F.Cu" "F.Mask" "F.Paste")
			(roundrect_rratio 0.25)
			(net 137 "QSPIA2_D1")
			(pinfunction "SO/IO1")
			(pintype "bidirectional")
		)
		(pad "3" smd roundrect
			(at -3.601 0.633 180)
			(size 0.65 1.65)
			(layers "F.Cu" "F.Mask" "F.Paste")
			(roundrect_rratio 0.25)
			(net 138 "QSPIA2_D2")
			(pinfunction "~{WP}/IO2")
			(pintype "bidirectional")
		)
		(pad "4" smd roundrect
			(at -3.601 1.904 180)
			(size 0.65 1.65)
			(layers "F.Cu" "F.Mask" "F.Paste")
			(roundrect_rratio 0.25)
			(net 1 "GND")
			(pinfunction "VSS")
			(pintype "power_in")
		)
		(pad "5" smd roundrect
			(at 3.6 1.904 180)
			(size 0.65 1.65)
			(layers "F.Cu" "F.Mask" "F.Paste")
			(roundrect_rratio 0.25)
			(net 136 "QSPIA2_D0")
			(pinfunction "SI/IO0")
			(pintype "bidirectional")
		)
		(pad "6" smd roundrect
			(at 3.6 0.633 180)
			(size 0.65 1.65)
			(layers "F.Cu" "F.Mask" "F.Paste")
			(roundrect_rratio 0.25)
			(net 130 "QSPIA_CLK")
			(pinfunction "SCLK")
			(pintype "input")
		)
		(pad "7" smd roundrect
			(at 3.6 -0.635 180)
			(size 0.65 1.65)
			(layers "F.Cu" "F.Mask" "F.Paste")
			(roundrect_rratio 0.25)
			(net 139 "QSPIA2_D3")
			(pinfunction "~{HOLD}/IO3")
			(pintype "bidirectional")
		)
		(pad "8" smd roundrect
			(at 3.6 -1.905 180)
			(size 0.65 1.65)
			(layers "F.Cu" "F.Mask" "F.Paste")
			(roundrect_rratio 0.25)
			(net 2 "VCC3V3")
			(pinfunction "VCC")
			(pintype "power_in")
		)
	)
)
